# S9S_MB_2U (Grand Teton) — schematic netlist excerpt (pin names and nets, part order shuffled) for the footprints in the layout excerpt that follows; sources: Cadence DE-HDL packaged netlist, KiCad conversion of 03242023_DA0F0TMBIJ0_F0T_Motherboard_J_brd_V01_OCP.brd

PC1349  Q_CAP  0.1UF 25V 10% X7R  pkg 0402  page 271 : A = GND ; B = PVCCIN_CPU0_VREF
R3439  Q_RES  4.7K 5% CHIP  pkg 0402LF  page 147 : A = P3V3_AUX ; B = GPU_FPGA_THERM_OVERT_ISO_N

(kicad_pcb
	(version 20260206)
	(generator "pcbnew")
	(generator_version "10.0")
	(general
		(thickness 1.6)
		(legacy_teardrops no)
	)
	(paper "A4")
	(title_block
		(title "03242023_DA0F0TMBIJ0_F0T_Motherboard_J_brd_V01_OCP.brd")
		(comment 1 "Grand Teton / footprints 3939-3940 of 6105")
	)
	(layers
		(0 "F.Cu" signal "TOP")
		(4 "In1.Cu" signal "GND")
		(6 "In2.Cu" signal "IN1")
		(8 "In3.Cu" signal "GND1")
		(10 "In4.Cu" signal "IN2")
		(12 "In5.Cu" signal "GND2")
		(14 "In6.Cu" signal "IN3")
		(16 "In7.Cu" signal "GND3")
		(18 "In8.Cu" signal "VCC")
		(20 "In9.Cu" signal "VCC1")
		(22 "In10.Cu" signal "GND4")
		(24 "In11.Cu" signal "IN4")
		(26 "In12.Cu" signal "GND5")
		(28 "In13.Cu" signal "IN5")
		(30 "In14.Cu" signal "GND6")
		(32 "In15.Cu" signal "IN6")
		(34 "In16.Cu" signal "GND7")
		(2 "B.Cu" signal "BOTTOM")
		(9 "F.Adhes" user "F.Adhesive")
		(11 "B.Adhes" user "B.Adhesive")
		(13 "F.Paste" user "Package Geometry/Pastemask Top")
		(15 "B.Paste" user "Package Geometry/Pastemask Bottom")
		(5 "F.SilkS" user "Ref Des/Silkscreen Top")
		(7 "B.SilkS" user "Ref Des/Silkscreen Bottom")
		(1 "F.Mask" user "Board Geometry/Soldermask Top")
		(3 "B.Mask" user "Board Geometry/Soldermask Bottom")
		(17 "Dwgs.User" user "User.Drawings")
		(19 "Cmts.User" user "User.Comments")
		(21 "Eco1.User" user "User.Eco1")
		(23 "Eco2.User" user "User.Eco2")
		(25 "Edge.Cuts" user "Board Geometry/Outline")
		(27 "Margin" user)
		(31 "F.CrtYd" user "Package Geometry/Place Bound Top")
		(29 "B.CrtYd" user "Package Geometry/Place Bound Bottom")
		(35 "F.Fab" user "Ref Des/Assembly Top")
		(33 "B.Fab" user "Ref Des/Assembly Bottom")
	)
	(footprint ""
		(layer "F.Cu")
		(at 413.408114 -366.66932 -90)
		(property "Reference" "PC1349"
			(at 0 0 270)
			(layer "F.SilkS")
			(hide yes)
			(effects
				(font
					(size 1.27 1.27)
				)
			)
		)
		(property "Value" ""
			(at 0 0 270)
			(layer "F.Fab")
			(effects
				(font
					(size 1.27 1.27)
				)
			)
		)
		(duplicate_pad_numbers_are_jumpers no)
		(fp_line
			(start -0.7874 0.4064)
			(end -0.7874 -0.4064)
			(stroke
				(width 0.1524)
				(type default)
			)
			(layer "F.SilkS")
		)
		(fp_line
			(start 0.7874 0.4064)
			(end -0.7874 0.4064)
			(stroke
				(width 0.1524)
				(type default)
			)
			(layer "F.SilkS")
		)
		(fp_line
			(start -0.7874 -0.4064)
			(end 0.7874 -0.4064)
			(stroke
				(width 0.1524)
				(type default)
			)
			(layer "F.SilkS")
		)
		(fp_line
			(start 0.7874 -0.4064)
			(end 0.7874 0.4064)
			(stroke
				(width 0.1524)
				(type default)
			)
			(layer "F.SilkS")
		)
		(fp_line
			(start -0.67945 0.3048)
			(end -0.67945 -0.305054)
			(stroke
				(width 0.1)
				(type default)
			)
			(layer "F.Fab")
		)
		(fp_line
			(start -0.12065 0.3048)
			(end -0.67945 0.3048)
			(stroke
				(width 0.1)
				(type default)
			)
			(layer "F.Fab")
		)
		(fp_line
			(start 0.120396 0.3048)
			(end 0.120396 0.2794)
			(stroke
				(width 0.1)
				(type default)
			)
			(layer "F.Fab")
		)
		(fp_line
			(start 0.67945 0.3048)
			(end 0.120396 0.3048)
			(stroke
				(width 0.1)
				(type default)
			)
			(layer "F.Fab")
		)
		(fp_line
			(start -0.12065 0.2794)
			(end -0.12065 0.3048)
			(stroke
				(width 0.1)
				(type default)
			)
			(layer "F.Fab")
		)
		(fp_line
			(start 0.120396 0.2794)
			(end -0.12065 0.2794)
			(stroke
				(width 0.1)
				(type default)
			)
			(layer "F.Fab")
		)
		(fp_line
			(start -0.12065 -0.2794)
			(end 0.12065 -0.2794)
			(stroke
				(width 0.1)
				(type default)
			)
			(layer "F.Fab")
		)
		(fp_line
			(start 0.12065 -0.2794)
			(end 0.12065 -0.3048)
			(stroke
				(width 0.1)
				(type default)
			)
			(layer "F.Fab")
		)
		(fp_line
			(start 0.12065 -0.3048)
			(end 0.67945 -0.3048)
			(stroke
				(width 0.1)
				(type default)
			)
			(layer "F.Fab")
		)
		(fp_line
			(start 0.67945 -0.3048)
			(end 0.67945 0.3048)
			(stroke
				(width 0.1)
				(type default)
			)
			(layer "F.Fab")
		)
		(fp_line
			(start -0.67945 -0.305054)
			(end -0.12065 -0.305054)
			(stroke
				(width 0.1)
				(type default)
			)
			(layer "F.Fab")
		)
		(fp_line
			(start -0.12065 -0.305054)
			(end -0.12065 -0.2794)
			(stroke
				(width 0.1)
				(type default)
			)
			(layer "F.Fab")
		)
		(pad "1" smd circle
			(at -0.40005 0 270)
			(size 0 0)
			(layers "F.Cu" "F.Mask" "F.Paste")
			(net "GND")
		)
		(pad "2" smd circle
			(at 0.40005 0 270)
			(size 0 0)
			(layers "F.Cu" "F.Mask" "F.Paste")
			(net "PVCCIN_CPU0_VREF")
		)
	)
	(footprint ""
		(layer "F.Cu")
		(at 24.050752 -405.858218)
		(property "Reference" "R3439"
			(at 0 0 0)
			(layer "F.SilkS")
			(hide yes)
			(effects
				(font
					(size 1.27 1.27)
				)
			)
		)
		(property "Value" ""
			(at 0 0 0)
			(layer "F.Fab")
			(effects
				(font
					(size 1.27 1.27)
				)
			)
		)
		(duplicate_pad_numbers_are_jumpers no)
		(fp_line
			(start -0.7874 -0.4064)
			(end 0.7874 -0.4064)
			(stroke
				(width 0.1524)
				(type default)
			)
			(layer "F.SilkS")
		)
		(fp_line
			(start -0.7874 0.4064)
			(end -0.7874 -0.4064)
			(stroke
				(width 0.1524)
				(type default)
			)
			(layer "F.SilkS")
		)
		(fp_line
			(start 0.7874 -0.4064)
			(end 0.7874 0.4064)
			(stroke
				(width 0.1524)
				(type default)
			)
			(layer "F.SilkS")
		)
		(fp_line
			(start 0.7874 0.4064)
			(end -0.7874 0.4064)
			(stroke
				(width 0.1524)
				(type default)
			)
			(layer "F.SilkS")
		)
		(fp_line
			(start -0.67945 -0.305054)
			(end -0.12065 -0.305054)
			(stroke
				(width 0.1)
				(type default)
			)
			(layer "F.Fab")
		)
		(fp_line
			(start -0.67945 0.3048)
			(end -0.67945 -0.305054)
			(stroke
				(width 0.1)
				(type default)
			)
			(layer "F.Fab")
		)
		(fp_line
			(start -0.12065 -0.305054)
			(end -0.12065 -0.2794)
			(stroke
				(width 0.1)
				(type default)
			)
			(layer "F.Fab")
		)
		(fp_line
			(start -0.12065 -0.2794)
			(end 0.12065 -0.2794)
			(stroke
				(width 0.1)
				(type default)
			)
			(layer "F.Fab")
		)
		(fp_line
			(start -0.12065 0.2794)
			(end -0.12065 0.3048)
			(stroke
				(width 0.1)
				(type default)
			)
			(layer "F.Fab")
		)
		(fp_line
			(start -0.12065 0.3048)
			(end -0.67945 0.3048)
			(stroke
				(width 0.1)
				(type default)
			)
			(layer "F.Fab")
		)
		(fp_line
			(start 0.120396 0.2794)
			(end -0.12065 0.2794)
			(stroke
				(width 0.1)
				(type default)
			)
			(layer "F.Fab")
		)
		(fp_line
			(start 0.120396 0.3048)
			(end 0.120396 0.2794)
			(stroke
				(width 0.1)
				(type default)
			)
			(layer "F.Fab")
		)
		(fp_line
			(start 0.12065 -0.3048)
			(end 0.67945 -0.3048)
			(stroke
				(width 0.1)
				(type default)
			)
			(layer "F.Fab")
		)
		(fp_line
			(start 0.12065 -0.2794)
			(end 0.12065 -0.3048)
			(stroke
				(width 0.1)
				(type default)
			)
			(layer "F.Fab")
		)
		(fp_line
			(start 0.67945 -0.3048)
			(end 0.67945 0.3048)
			(stroke
				(width 0.1)
				(type default)
			)
			(layer "F.Fab")
		)
		(fp_line
			(start 0.67945 0.3048)
			(end 0.120396 0.3048)
			(stroke
				(width 0.1)
				(type default)
			)
			(layer "F.Fab")
		)
		(pad "1" smd circle
			(at -0.40005 0)
			(size 0 0)
			(layers "F.Cu" "F.Mask" "F.Paste")
			(net "P3V3_AUX")
		)
		(pad "2" smd circle
			(at 0.40005 0)
			(size 0 0)
			(layers "F.Cu" "F.Mask" "F.Paste")
			(net "GPU_FPGA_THERM_OVERT_ISO_N")
		)
	)
)
